(kicad_pcb
	(version 20260206)
	(generator "pcbnew")
	(generator_version "10.0")
	(general
		(thickness 1.6)
		(legacy_teardrops no)
	)
	(paper "A4")
	(title_block
		(title "03242023_DA0F0TMBIJ0_F0T_Motherboard_J_brd_V01_OCP.brd")
		(comment 1 "Grand Teton / footprints 4507-4513 of 6105")
	)
	(layers
		(0 "F.Cu" signal "TOP")
		(4 "In1.Cu" signal "GND")
		(6 "In2.Cu" signal "IN1")
		(8 "In3.Cu" signal "GND1")
		(10 "In4.Cu" signal "IN2")
		(12 "In5.Cu" signal "GND2")
		(14 "In6.Cu" signal "IN3")
		(16 "In7.Cu" signal "GND3")
		(18 "In8.Cu" signal "VCC")
		(20 "In9.Cu" signal "VCC1")
		(22 "In10.Cu" signal "GND4")
		(24 "In11.Cu" signal "IN4")
		(26 "In12.Cu" signal "GND5")
		(28 "In13.Cu" signal "IN5")
		(30 "In14.Cu" signal "GND6")
		(32 "In15.Cu" signal "IN6")
		(34 "In16.Cu" signal "GND7")
		(2 "B.Cu" signal "BOTTOM")
		(9 "F.Adhes" user "F.Adhesive")
		(11 "B.Adhes" user "B.Adhesive")
		(13 "F.Paste" user "Package Geometry/Pastemask Top")
		(15 "B.Paste" user "Package Geometry/Pastemask Bottom")
		(5 "F.SilkS" user "Ref Des/Silkscreen Top")
		(7 "B.SilkS" user "Ref Des/Silkscreen Bottom")
		(1 "F.Mask" user "Board Geometry/Soldermask Top")
		(3 "B.Mask" user "Board Geometry/Soldermask Bottom")
		(17 "Dwgs.User" user "User.Drawings")
		(19 "Cmts.User" user "User.Comments")
		(21 "Eco1.User" user "User.Eco1")
		(23 "Eco2.User" user "User.Eco2")
		(25 "Edge.Cuts" user "Board Geometry/Outline")
		(27 "Margin" user)
		(31 "F.CrtYd" user "Package Geometry/Place Bound Top")
		(29 "B.CrtYd" user "Package Geometry/Place Bound Bottom")
		(35 "F.Fab" user "Ref Des/Assembly Top")
		(33 "B.Fab" user "Ref Des/Assembly Bottom")
	)
	(footprint ""
		(layer "B.Cu")
		(at 369.49888 -41.112948 180)
		(property "Reference" "R4111"
			(at 0 0 0)
			(layer "B.SilkS")
			(hide yes)
			(effects
				(font
					(size 1.27 1.27)
				)
				(justify mirror)
			)
		)
		(property "Value" ""
			(at 0 0 0)
			(layer "B.Fab")
			(effects
				(font
					(size 1.27 1.27)
				)
				(justify mirror)
			)
		)
		(duplicate_pad_numbers_are_jumpers no)
		(fp_line
			(start 0.7874 0.4064)
			(end 0.7874 -0.4064)
			(stroke
				(width 0.1524)
				(type default)
			)
			(layer "B.SilkS")
		)
		(fp_line
			(start 0.7874 -0.4064)
			(end -0.7874 -0.4064)
			(stroke
				(width 0.1524)
				(type default)
			)
			(layer "B.SilkS")
		)
		(fp_line
			(start -0.7874 0.4064)
			(end 0.7874 0.4064)
			(stroke
				(width 0.1524)
				(type default)
			)
			(layer "B.SilkS")
		)
		(fp_line
			(start -0.7874 -0.4064)
			(end -0.7874 0.4064)
			(stroke
				(width 0.1524)
				(type default)
			)
			(layer "B.SilkS")
		)
		(fp_line
			(start 0.67945 0.3048)
			(end 0.67945 -0.305054)
			(stroke
				(width 0.1)
				(type default)
			)
			(layer "B.Fab")
		)
		(fp_line
			(start 0.67945 -0.305054)
			(end 0.12065 -0.305054)
			(stroke
				(width 0.1)
				(type default)
			)
			(layer "B.Fab")
		)
		(fp_line
			(start 0.12065 0.3048)
			(end 0.67945 0.3048)
			(stroke
				(width 0.1)
				(type default)
			)
			(layer "B.Fab")
		)
		(fp_line
			(start 0.12065 0.2794)
			(end 0.12065 0.3048)
			(stroke
				(width 0.1)
				(type default)
			)
			(layer "B.Fab")
		)
		(fp_line
			(start 0.12065 -0.2794)
			(end -0.12065 -0.2794)
			(stroke
				(width 0.1)
				(type default)
			)
			(layer "B.Fab")
		)
		(fp_line
			(start 0.12065 -0.305054)
			(end 0.12065 -0.2794)
			(stroke
				(width 0.1)
				(type default)
			)
			(layer "B.Fab")
		)
		(fp_line
			(start -0.120396 0.3048)
			(end -0.120396 0.2794)
			(stroke
				(width 0.1)
				(type default)
			)
			(layer "B.Fab")
		)
		(fp_line
			(start -0.120396 0.2794)
			(end 0.12065 0.2794)
			(stroke
				(width 0.1)
				(type default)
			)
			(layer "B.Fab")
		)
		(fp_line
			(start -0.12065 -0.2794)
			(end -0.12065 -0.3048)
			(stroke
				(width 0.1)
				(type default)
			)
			(layer "B.Fab")
		)
		(fp_line
			(start -0.12065 -0.3048)
			(end -0.67945 -0.3048)
			(stroke
				(width 0.1)
				(type default)
			)
			(layer "B.Fab")
		)
		(fp_line
			(start -0.67945 0.3048)
			(end -0.120396 0.3048)
			(stroke
				(width 0.1)
				(type default)
			)
			(layer "B.Fab")
		)
		(fp_line
			(start -0.67945 -0.3048)
			(end -0.67945 0.3048)
			(stroke
				(width 0.1)
				(type default)
			)
			(layer "B.Fab")
		)
		(pad "1" smd circle
			(at 0.40005 0)
			(size 0 0)
			(layers "B.Cu" "B.Mask" "B.Paste")
			(net "PD_PCH_GPP_E_13")
		)
		(pad "2" smd circle
			(at -0.40005 0)
			(size 0 0)
			(layers "B.Cu" "B.Mask" "B.Paste")
			(net "GND")
		)
	)
	(footprint ""
		(layer "B.Cu")
		(at 350.435418 -294.009826 180)
		(property "Reference" "C366"
			(at 0 0 0)
			(layer "B.SilkS")
			(hide yes)
			(effects
				(font
					(size 1.27 1.27)
				)
				(justify mirror)
			)
		)
		(property "Value" ""
			(at 0 0 0)
			(layer "B.Fab")
			(effects
				(font
					(size 1.27 1.27)
				)
				(justify mirror)
			)
		)
		(duplicate_pad_numbers_are_jumpers no)
		(fp_line
			(start 1.524 0.762)
			(end 1.524 -0.762)
			(stroke
				(width 0.1524)
				(type default)
			)
			(layer "B.SilkS")
		)
		(fp_line
			(start 1.524 -0.762)
			(end -1.524 -0.762)
			(stroke
				(width 0.1524)
				(type default)
			)
			(layer "B.SilkS")
		)
		(fp_line
			(start -1.524 0.762)
			(end 1.524 0.762)
			(stroke
				(width 0.1524)
				(type default)
			)
			(layer "B.SilkS")
		)
		(fp_line
			(start -1.524 -0.762)
			(end -1.524 0.762)
			(stroke
				(width 0.1524)
				(type default)
			)
			(layer "B.SilkS")
		)
		(fp_line
			(start 1.1049 0.724916)
			(end -1.1049 0.724916)
			(stroke
				(width 0.1)
				(type default)
			)
			(layer "B.Fab")
		)
		(fp_line
			(start 1.1049 -0.724916)
			(end 1.1049 0.724916)
			(stroke
				(width 0.1)
				(type default)
			)
			(layer "B.Fab")
		)
		(fp_line
			(start -1.1049 0.724916)
			(end -1.1049 -0.724916)
			(stroke
				(width 0.1)
				(type default)
			)
			(layer "B.Fab")
		)
		(fp_line
			(start -1.1049 -0.724916)
			(end 1.1049 -0.724916)
			(stroke
				(width 0.1)
				(type default)
			)
			(layer "B.Fab")
		)
		(pad "1" smd rect
			(at 0.889 0 180)
			(size 1.016 1.27)
			(layers "B.Cu" "B.Mask" "B.Paste")
			(net "PVCCIN_CPU0")
		)
		(pad "2" smd rect
			(at -0.889 0 180)
			(size 1.016 1.27)
			(layers "B.Cu" "B.Mask" "B.Paste")
			(net "GND")
		)
	)
	(footprint ""
		(layer "B.Cu")
		(at 362.56341 -357.690166)
		(property "Reference" "PR159"
			(at 0 0 0)
			(layer "B.SilkS")
			(hide yes)
			(effects
				(font
					(size 1.27 1.27)
				)
				(justify mirror)
			)
		)
		(property "Value" ""
			(at 0 0 0)
			(layer "B.Fab")
			(effects
				(font
					(size 1.27 1.27)
				)
				(justify mirror)
			)
		)
		(duplicate_pad_numbers_are_jumpers no)
		(fp_line
			(start -0.7874 -0.4064)
			(end -0.7874 0.4064)
			(stroke
				(width 0.1524)
				(type default)
			)
			(layer "B.SilkS")
		)
		(fp_line
			(start -0.7874 0.4064)
			(end 0.7874 0.4064)
			(stroke
				(width 0.1524)
				(type default)
			)
			(layer "B.SilkS")
		)
		(fp_line
			(start 0.7874 -0.4064)
			(end -0.7874 -0.4064)
			(stroke
				(width 0.1524)
				(type default)
			)
			(layer "B.SilkS")
		)
		(fp_line
			(start 0.7874 0.4064)
			(end 0.7874 -0.4064)
			(stroke
				(width 0.1524)
				(type default)
			)
			(layer "B.SilkS")
		)
		(fp_line
			(start -0.67945 -0.3048)
			(end -0.67945 0.3048)
			(stroke
				(width 0.1)
				(type default)
			)
			(layer "B.Fab")
		)
		(fp_line
			(start -0.67945 0.3048)
			(end -0.120396 0.3048)
			(stroke
				(width 0.1)
				(type default)
			)
			(layer "B.Fab")
		)
		(fp_line
			(start -0.12065 -0.3048)
			(end -0.67945 -0.3048)
			(stroke
				(width 0.1)
				(type default)
			)
			(layer "B.Fab")
		)
		(fp_line
			(start -0.12065 -0.2794)
			(end -0.12065 -0.3048)
			(stroke
				(width 0.1)
				(type default)
			)
			(layer "B.Fab")
		)
		(fp_line
			(start -0.120396 0.2794)
			(end 0.12065 0.2794)
			(stroke
				(width 0.1)
				(type default)
			)
			(layer "B.Fab")
		)
		(fp_line
			(start -0.120396 0.3048)
			(end -0.120396 0.2794)
			(stroke
				(width 0.1)
				(type default)
			)
			(layer "B.Fab")
		)
		(fp_line
			(start 0.12065 -0.305054)
			(end 0.12065 -0.2794)
			(stroke
				(width 0.1)
				(type default)
			)
			(layer "B.Fab")
		)
		(fp_line
			(start 0.12065 -0.2794)
			(end -0.12065 -0.2794)
			(stroke
				(width 0.1)
				(type default)
			)
			(layer "B.Fab")
		)
		(fp_line
			(start 0.12065 0.2794)
			(end 0.12065 0.3048)
			(stroke
				(width 0.1)
				(type default)
			)
			(layer "B.Fab")
		)
		(fp_line
			(start 0.12065 0.3048)
			(end 0.67945 0.3048)
			(stroke
				(width 0.1)
				(type default)
			)
			(layer "B.Fab")
		)
		(fp_line
			(start 0.67945 -0.305054)
			(end 0.12065 -0.305054)
			(stroke
				(width 0.1)
				(type default)
			)
			(layer "B.Fab")
		)
		(fp_line
			(start 0.67945 0.3048)
			(end 0.67945 -0.305054)
			(stroke
				(width 0.1)
				(type default)
			)
			(layer "B.Fab")
		)
		(pad "1" smd circle
			(at 0.40005 0 180)
			(size 0 0)
			(layers "B.Cu" "B.Mask" "B.Paste")
			(net "PVCCIN_CPU0_VREF")
		)
		(pad "2" smd circle
			(at -0.40005 0 180)
			(size 0 0)
			(layers "B.Cu" "B.Mask" "B.Paste")
			(net "PVCCIN_CPU0_ADDR")
		)
	)
	(footprint ""
		(layer "B.Cu")
		(at 416.287712 -193.08953 -90)
		(property "Reference" "R321"
			(at 0 0 90)
			(layer "B.SilkS")
			(hide yes)
			(effects
				(font
					(size 1.27 1.27)
				)
				(justify mirror)
			)
		)
		(property "Value" ""
			(at 0 0 90)
			(layer "B.Fab")
			(effects
				(font
					(size 1.27 1.27)
				)
				(justify mirror)
			)
		)
		(duplicate_pad_numbers_are_jumpers no)
		(fp_line
			(start -0.7874 0.4064)
			(end 0.7874 0.4064)
			(stroke
				(width 0.1524)
				(type default)
			)
			(layer "B.SilkS")
		)
		(fp_line
			(start 0.7874 0.4064)
			(end 0.7874 -0.4064)
			(stroke
				(width 0.1524)
				(type default)
			)
			(layer "B.SilkS")
		)
		(fp_line
			(start -0.7874 -0.4064)
			(end -0.7874 0.4064)
			(stroke
				(width 0.1524)
				(type default)
			)
			(layer "B.SilkS")
		)
		(fp_line
			(start 0.7874 -0.4064)
			(end -0.7874 -0.4064)
			(stroke
				(width 0.1524)
				(type default)
			)
			(layer "B.SilkS")
		)
		(fp_line
			(start -0.67945 0.3048)
			(end -0.120396 0.3048)
			(stroke
				(width 0.1)
				(type default)
			)
			(layer "B.Fab")
		)
		(fp_line
			(start -0.120396 0.3048)
			(end -0.120396 0.2794)
			(stroke
				(width 0.1)
				(type default)
			)
			(layer "B.Fab")
		)
		(fp_line
			(start 0.12065 0.3048)
			(end 0.67945 0.3048)
			(stroke
				(width 0.1)
				(type default)
			)
			(layer "B.Fab")
		)
		(fp_line
			(start 0.67945 0.3048)
			(end 0.67945 -0.305054)
			(stroke
				(width 0.1)
				(type default)
			)
			(layer "B.Fab")
		)
		(fp_line
			(start -0.120396 0.2794)
			(end 0.12065 0.2794)
			(stroke
				(width 0.1)
				(type default)
			)
			(layer "B.Fab")
		)
		(fp_line
			(start 0.12065 0.2794)
			(end 0.12065 0.3048)
			(stroke
				(width 0.1)
				(type default)
			)
			(layer "B.Fab")
		)
		(fp_line
			(start -0.12065 -0.2794)
			(end -0.12065 -0.3048)
			(stroke
				(width 0.1)
				(type default)
			)
			(layer "B.Fab")
		)
		(fp_line
			(start 0.12065 -0.2794)
			(end -0.12065 -0.2794)
			(stroke
				(width 0.1)
				(type default)
			)
			(layer "B.Fab")
		)
		(fp_line
			(start -0.67945 -0.3048)
			(end -0.67945 0.3048)
			(stroke
				(width 0.1)
				(type default)
			)
			(layer "B.Fab")
		)
		(fp_line
			(start -0.12065 -0.3048)
			(end -0.67945 -0.3048)
			(stroke
				(width 0.1)
				(type default)
			)
			(layer "B.Fab")
		)
		(fp_line
			(start 0.12065 -0.305054)
			(end 0.12065 -0.2794)
			(stroke
				(width 0.1)
				(type default)
			)
			(layer "B.Fab")
		)
		(fp_line
			(start 0.67945 -0.305054)
			(end 0.12065 -0.305054)
			(stroke
				(width 0.1)
				(type default)
			)
			(layer "B.Fab")
		)
		(pad "1" smd circle
			(at 0.40005 0 90)
			(size 0 0)
			(layers "B.Cu" "B.Mask" "B.Paste")
			(net "P3V3_AUX")
		)
		(pad "2" smd circle
			(at -0.40005 0 90)
			(size 0 0)
			(layers "B.Cu" "B.Mask" "B.Paste")
			(net "FM_S3M_CPU0_CPLD_CONFIG_N")
		)
	)
	(footprint ""
		(layer "B.Cu")
		(at 154.00782 -13.762228 90)
		(property "Reference" "R2415"
			(at 0 0 90)
			(layer "B.SilkS")
			(hide yes)
			(effects
				(font
					(size 1.27 1.27)
				)
				(justify mirror)
			)
		)
		(property "Value" ""
			(at 0 0 90)
			(layer "B.Fab")
			(effects
				(font
					(size 1.27 1.27)
				)
				(justify mirror)
			)
		)
		(duplicate_pad_numbers_are_jumpers no)
		(fp_line
			(start 0.7874 -0.4064)
			(end -0.7874 -0.4064)
			(stroke
				(width 0.1524)
				(type default)
			)
			(layer "B.SilkS")
		)
		(fp_line
			(start -0.7874 -0.4064)
			(end -0.7874 0.4064)
			(stroke
				(width 0.1524)
				(type default)
			)
			(layer "B.SilkS")
		)
		(fp_line
			(start 0.7874 0.4064)
			(end 0.7874 -0.4064)
			(stroke
				(width 0.1524)
				(type default)
			)
			(layer "B.SilkS")
		)
		(fp_line
			(start -0.7874 0.4064)
			(end 0.7874 0.4064)
			(stroke
				(width 0.1524)
				(type default)
			)
			(layer "B.SilkS")
		)
		(fp_line
			(start 0.67945 -0.305054)
			(end 0.12065 -0.305054)
			(stroke
				(width 0.1)
				(type default)
			)
			(layer "B.Fab")
		)
		(fp_line
			(start 0.12065 -0.305054)
			(end 0.12065 -0.2794)
			(stroke
				(width 0.1)
				(type default)
			)
			(layer "B.Fab")
		)
		(fp_line
			(start -0.12065 -0.3048)
			(end -0.67945 -0.3048)
			(stroke
				(width 0.1)
				(type default)
			)
			(layer "B.Fab")
		)
		(fp_line
			(start -0.67945 -0.3048)
			(end -0.67945 0.3048)
			(stroke
				(width 0.1)
				(type default)
			)
			(layer "B.Fab")
		)
		(fp_line
			(start 0.12065 -0.2794)
			(end -0.12065 -0.2794)
			(stroke
				(width 0.1)
				(type default)
			)
			(layer "B.Fab")
		)
		(fp_line
			(start -0.12065 -0.2794)
			(end -0.12065 -0.3048)
			(stroke
				(width 0.1)
				(type default)
			)
			(layer "B.Fab")
		)
		(fp_line
			(start 0.12065 0.2794)
			(end 0.12065 0.3048)
			(stroke
				(width 0.1)
				(type default)
			)
			(layer "B.Fab")
		)
		(fp_line
			(start -0.120396 0.2794)
			(end 0.12065 0.2794)
			(stroke
				(width 0.1)
				(type default)
			)
			(layer "B.Fab")
		)
		(fp_line
			(start 0.67945 0.3048)
			(end 0.67945 -0.305054)
			(stroke
				(width 0.1)
				(type default)
			)
			(layer "B.Fab")
		)
		(fp_line
			(start 0.12065 0.3048)
			(end 0.67945 0.3048)
			(stroke
				(width 0.1)
				(type default)
			)
			(layer "B.Fab")
		)
		(fp_line
			(start -0.120396 0.3048)
			(end -0.120396 0.2794)
			(stroke
				(width 0.1)
				(type default)
			)
			(layer "B.Fab")
		)
		(fp_line
			(start -0.67945 0.3048)
			(end -0.120396 0.3048)
			(stroke
				(width 0.1)
				(type default)
			)
			(layer "B.Fab")
		)
		(pad "1" smd circle
			(at 0.40005 0 270)
			(size 0 0)
			(layers "B.Cu" "B.Mask" "B.Paste")
			(net "SMB_1_BMC_GPU_SCL")
		)
		(pad "2" smd circle
			(at -0.40005 0 270)
			(size 0 0)
			(layers "B.Cu" "B.Mask" "B.Paste")
			(net "SMB_PCIE3_3V3AUX_SCL_R")
		)
	)
	(footprint ""
		(layer "B.Cu")
		(at 382.009904 -188.29401)
		(property "Reference" "R1216"
			(at 0 0 0)
			(layer "B.SilkS")
			(hide yes)
			(effects
				(font
					(size 1.27 1.27)
				)
				(justify mirror)
			)
		)
		(property "Value" ""
			(at 0 0 0)
			(layer "B.Fab")
			(effects
				(font
					(size 1.27 1.27)
				)
				(justify mirror)
			)
		)
		(duplicate_pad_numbers_are_jumpers no)
		(fp_line
			(start -0.7874 -0.4064)
			(end -0.7874 0.4064)
			(stroke
				(width 0.1524)
				(type default)
			)
			(layer "B.SilkS")
		)
		(fp_line
			(start -0.7874 0.4064)
			(end 0.7874 0.4064)
			(stroke
				(width 0.1524)
				(type default)
			)
			(layer "B.SilkS")
		)
		(fp_line
			(start 0.7874 -0.4064)
			(end -0.7874 -0.4064)
			(stroke
				(width 0.1524)
				(type default)
			)
			(layer "B.SilkS")
		)
		(fp_line
			(start 0.7874 0.4064)
			(end 0.7874 -0.4064)
			(stroke
				(width 0.1524)
				(type default)
			)
			(layer "B.SilkS")
		)
		(fp_line
			(start -0.67945 -0.3048)
			(end -0.67945 0.3048)
			(stroke
				(width 0.1)
				(type default)
			)
			(layer "B.Fab")
		)
		(fp_line
			(start -0.67945 0.3048)
			(end -0.120396 0.3048)
			(stroke
				(width 0.1)
				(type default)
			)
			(layer "B.Fab")
		)
		(fp_line
			(start -0.12065 -0.3048)
			(end -0.67945 -0.3048)
			(stroke
				(width 0.1)
				(type default)
			)
			(layer "B.Fab")
		)
		(fp_line
			(start -0.12065 -0.2794)
			(end -0.12065 -0.3048)
			(stroke
				(width 0.1)
				(type default)
			)
			(layer "B.Fab")
		)
		(fp_line
			(start -0.120396 0.2794)
			(end 0.12065 0.2794)
			(stroke
				(width 0.1)
				(type default)
			)
			(layer "B.Fab")
		)
		(fp_line
			(start -0.120396 0.3048)
			(end -0.120396 0.2794)
			(stroke
				(width 0.1)
				(type default)
			)
			(layer "B.Fab")
		)
		(fp_line
			(start 0.12065 -0.305054)
			(end 0.12065 -0.2794)
			(stroke
				(width 0.1)
				(type default)
			)
			(layer "B.Fab")
		)
		(fp_line
			(start 0.12065 -0.2794)
			(end -0.12065 -0.2794)
			(stroke
				(width 0.1)
				(type default)
			)
			(layer "B.Fab")
		)
		(fp_line
			(start 0.12065 0.2794)
			(end 0.12065 0.3048)
			(stroke
				(width 0.1)
				(type default)
			)
			(layer "B.Fab")
		)
		(fp_line
			(start 0.12065 0.3048)
			(end 0.67945 0.3048)
			(stroke
				(width 0.1)
				(type default)
			)
			(layer "B.Fab")
		)
		(fp_line
			(start 0.67945 -0.305054)
			(end 0.12065 -0.305054)
			(stroke
				(width 0.1)
				(type default)
			)
			(layer "B.Fab")
		)
		(fp_line
			(start 0.67945 0.3048)
			(end 0.67945 -0.305054)
			(stroke
				(width 0.1)
				(type default)
			)
			(layer "B.Fab")
		)
		(pad "1" smd circle
			(at 0.40005 0 180)
			(size 0 0)
			(layers "B.Cu" "B.Mask" "B.Paste")
			(net "P3V3_AUX")
		)
		(pad "2" smd circle
			(at -0.40005 0 180)
			(size 0 0)
			(layers "B.Cu" "B.Mask" "B.Paste")
			(net "FM_S3M_CPU0_CPLD_CRC_ERROR")
		)
	)
	(footprint ""
		(layer "B.Cu")
		(at 354.601526 -337.564984 -90)
		(property "Reference" "PC302_P0_2"
			(at 0 0 90)
			(layer "B.SilkS")
			(hide yes)
			(effects
				(font
					(size 1.27 1.27)
				)
				(justify mirror)
			)
		)
		(property "Value" ""
			(at 0 0 90)
			(layer "B.Fab")
			(effects
				(font
					(size 1.27 1.27)
				)
				(justify mirror)
			)
		)
		(duplicate_pad_numbers_are_jumpers no)
		(fp_line
			(start -1.524 0.762)
			(end 1.524 0.762)
			(stroke
				(width 0.1524)
				(type default)
			)
			(layer "B.SilkS")
		)
		(fp_line
			(start 1.524 0.762)
			(end 1.524 -0.762)
			(stroke
				(width 0.1524)
				(type default)
			)
			(layer "B.SilkS")
		)
		(fp_line
			(start -1.524 -0.762)
			(end -1.524 0.762)
			(stroke
				(width 0.1524)
				(type default)
			)
			(layer "B.SilkS")
		)
		(fp_line
			(start 1.524 -0.762)
			(end -1.524 -0.762)
			(stroke
				(width 0.1524)
				(type default)
			)
			(layer "B.SilkS")
		)
		(fp_line
			(start -1.1049 0.724916)
			(end -1.1049 -0.724916)
			(stroke
				(width 0.1)
				(type default)
			)
			(layer "B.Fab")
		)
		(fp_line
			(start 1.1049 0.724916)
			(end -1.1049 0.724916)
			(stroke
				(width 0.1)
				(type default)
			)
			(layer "B.Fab")
		)
		(fp_line
			(start -1.1049 -0.724916)
			(end 1.1049 -0.724916)
			(stroke
				(width 0.1)
				(type default)
			)
			(layer "B.Fab")
		)
		(fp_line
			(start 1.1049 -0.724916)
			(end 1.1049 0.724916)
			(stroke
				(width 0.1)
				(type default)
			)
			(layer "B.Fab")
		)
		(pad "1" smd rect
			(at 0.889 0 270)
			(size 1.016 1.27)
			(layers "B.Cu" "B.Mask" "B.Paste")
			(net "SW_P12V_PVCCIN_CPU0_FLT")
		)
		(pad "2" smd rect
			(at -0.889 0 270)
			(size 1.016 1.27)
			(layers "B.Cu" "B.Mask" "B.Paste")
			(net "GND")
		)
	)
)
